# T6G (Grand Teton) — schematic netlist excerpt (pin names and nets, part order shuffled) for the footprints in the layout excerpt that follows; sources: Cadence DE-HDL packaged netlist, KiCad conversion of 04192023_DAF0TMB3IC0_F0TG_MB_C_brd_V02_OCP.brd

R768  Q_RES  54.9K 1% CHIP  pkg 0402LF  page 96 : A = PD_CHK_CPU0_DIMM_SAA ; B = GND
C6539  Q_CAP_DIFFBUS  DIFF BUS_0.22UF 6.3V 20% X6S  pkg C0201  page 286 : \1\ = P5E_CPU0_P1_TX_BUF_C_DP<3> ; \2\ = P5E_CPU0_P1_TX_BUF_DP<3>
C2526  Q_CAP  22UF 4V 20% X6S  pkg C0402  page 71 : A = PVDD18_S5_P0 ; B = GND

(kicad_pcb
	(version 20260206)
	(generator "pcbnew")
	(generator_version "10.0")
	(general
		(thickness 1.6)
		(legacy_teardrops no)
	)
	(paper "A4")
	(title_block
		(title "04192023_DAF0TMB3IC0_F0TG_MB_C_brd_V02_OCP.brd")
		(comment 1 "Grand Teton / footprints 6001-6003 of 8354")
	)
	(layers
		(0 "F.Cu" signal "TOP")
		(4 "In1.Cu" signal "GND")
		(6 "In2.Cu" signal "IN1")
		(8 "In3.Cu" signal "GND1")
		(10 "In4.Cu" signal "IN2")
		(12 "In5.Cu" signal "GND2")
		(14 "In6.Cu" signal "IN3")
		(16 "In7.Cu" signal "GND3")
		(18 "In8.Cu" signal "VCC")
		(20 "In9.Cu" signal "VCC1")
		(22 "In10.Cu" signal "GND4")
		(24 "In11.Cu" signal "IN4")
		(26 "In12.Cu" signal "GND5")
		(28 "In13.Cu" signal "IN5")
		(30 "In14.Cu" signal "GND6")
		(32 "In15.Cu" signal "IN6")
		(34 "In16.Cu" signal "GND7")
		(2 "B.Cu" signal "BOTTOM")
		(9 "F.Adhes" user "F.Adhesive")
		(11 "B.Adhes" user "B.Adhesive")
		(13 "F.Paste" user "Package Geometry/Pastemask Top")
		(15 "B.Paste" user "Package Geometry/Pastemask Bottom")
		(5 "F.SilkS" user "Ref Des/Silkscreen Top")
		(7 "B.SilkS" user "Ref Des/Silkscreen Bottom")
		(1 "F.Mask" user "Board Geometry/Soldermask Top")
		(3 "B.Mask" user "Board Geometry/Soldermask Bottom")
		(17 "Dwgs.User" user "User.Drawings")
		(19 "Cmts.User" user "User.Comments")
		(21 "Eco1.User" user "User.Eco1")
		(23 "Eco2.User" user "User.Eco2")
		(25 "Edge.Cuts" user "Board Geometry/Outline")
		(27 "Margin" user)
		(31 "F.CrtYd" user "Package Geometry/Place Bound Top")
		(29 "B.CrtYd" user "Package Geometry/Place Bound Bottom")
		(35 "F.Fab" user "Ref Des/Assembly Top")
		(33 "B.Fab" user "Ref Des/Assembly Bottom")
	)
	(footprint ""
		(layer "B.Cu")
		(at 353.900232 -255.554988 180)
		(property "Reference" "C2526"
			(at 0 0 0)
			(layer "B.SilkS")
			(hide yes)
			(effects
				(font
					(size 1.27 1.27)
				)
				(justify mirror)
			)
		)
		(property "Value" ""
			(at 0 0 0)
			(layer "B.Fab")
			(effects
				(font
					(size 1.27 1.27)
				)
				(justify mirror)
			)
		)
		(duplicate_pad_numbers_are_jumpers no)
		(fp_line
			(start 0.7874 0.4064)
			(end 0.7874 -0.4064)
			(stroke
				(width 0.1524)
				(type default)
			)
			(layer "B.SilkS")
		)
		(fp_line
			(start 0.7874 -0.4064)
			(end -0.7874 -0.4064)
			(stroke
				(width 0.1524)
				(type default)
			)
			(layer "B.SilkS")
		)
		(fp_line
			(start -0.7874 0.4064)
			(end 0.7874 0.4064)
			(stroke
				(width 0.1524)
				(type default)
			)
			(layer "B.SilkS")
		)
		(fp_line
			(start -0.7874 -0.4064)
			(end -0.7874 0.4064)
			(stroke
				(width 0.1524)
				(type default)
			)
			(layer "B.SilkS")
		)
		(fp_line
			(start 0.67945 0.3048)
			(end 0.67945 -0.305054)
			(stroke
				(width 0.1)
				(type default)
			)
			(layer "B.Fab")
		)
		(fp_line
			(start 0.67945 -0.305054)
			(end 0.12065 -0.305054)
			(stroke
				(width 0.1)
				(type default)
			)
			(layer "B.Fab")
		)
		(fp_line
			(start 0.12065 0.3048)
			(end 0.67945 0.3048)
			(stroke
				(width 0.1)
				(type default)
			)
			(layer "B.Fab")
		)
		(fp_line
			(start 0.12065 0.2794)
			(end 0.12065 0.3048)
			(stroke
				(width 0.1)
				(type default)
			)
			(layer "B.Fab")
		)
		(fp_line
			(start 0.12065 -0.2794)
			(end -0.12065 -0.2794)
			(stroke
				(width 0.1)
				(type default)
			)
			(layer "B.Fab")
		)
		(fp_line
			(start 0.12065 -0.305054)
			(end 0.12065 -0.2794)
			(stroke
				(width 0.1)
				(type default)
			)
			(layer "B.Fab")
		)
		(fp_line
			(start -0.120396 0.3048)
			(end -0.120396 0.2794)
			(stroke
				(width 0.1)
				(type default)
			)
			(layer "B.Fab")
		)
		(fp_line
			(start -0.120396 0.2794)
			(end 0.12065 0.2794)
			(stroke
				(width 0.1)
				(type default)
			)
			(layer "B.Fab")
		)
		(fp_line
			(start -0.12065 -0.2794)
			(end -0.12065 -0.3048)
			(stroke
				(width 0.1)
				(type default)
			)
			(layer "B.Fab")
		)
		(fp_line
			(start -0.12065 -0.3048)
			(end -0.67945 -0.3048)
			(stroke
				(width 0.1)
				(type default)
			)
			(layer "B.Fab")
		)
		(fp_line
			(start -0.67945 0.3048)
			(end -0.120396 0.3048)
			(stroke
				(width 0.1)
				(type default)
			)
			(layer "B.Fab")
		)
		(fp_line
			(start -0.67945 -0.3048)
			(end -0.67945 0.3048)
			(stroke
				(width 0.1)
				(type default)
			)
			(layer "B.Fab")
		)
		(pad "1" smd circle
			(at 0.40005 0)
			(size 0 0)
			(layers "B.Cu" "B.Mask" "B.Paste")
			(net "PVDD18_S5_P0")
		)
		(pad "2" smd circle
			(at -0.40005 0)
			(size 0 0)
			(layers "B.Cu" "B.Mask" "B.Paste")
			(net "GND")
		)
	)
	(footprint ""
		(layer "B.Cu")
		(at 443.29985 -194.88531 180)
		(property "Reference" "R768"
			(at 0 0 0)
			(layer "B.SilkS")
			(hide yes)
			(effects
				(font
					(size 1.27 1.27)
				)
				(justify mirror)
			)
		)
		(property "Value" ""
			(at 0 0 0)
			(layer "B.Fab")
			(effects
				(font
					(size 1.27 1.27)
				)
				(justify mirror)
			)
		)
		(duplicate_pad_numbers_are_jumpers no)
		(fp_line
			(start 0.7874 0.4064)
			(end 0.7874 -0.4064)
			(stroke
				(width 0.1524)
				(type default)
			)
			(layer "B.SilkS")
		)
		(fp_line
			(start 0.7874 -0.4064)
			(end -0.7874 -0.4064)
			(stroke
				(width 0.1524)
				(type default)
			)
			(layer "B.SilkS")
		)
		(fp_line
			(start -0.7874 0.4064)
			(end 0.7874 0.4064)
			(stroke
				(width 0.1524)
				(type default)
			)
			(layer "B.SilkS")
		)
		(fp_line
			(start -0.7874 -0.4064)
			(end -0.7874 0.4064)
			(stroke
				(width 0.1524)
				(type default)
			)
			(layer "B.SilkS")
		)
		(fp_line
			(start 0.67945 0.3048)
			(end 0.67945 -0.305054)
			(stroke
				(width 0.1)
				(type default)
			)
			(layer "B.Fab")
		)
		(fp_line
			(start 0.67945 -0.305054)
			(end 0.12065 -0.305054)
			(stroke
				(width 0.1)
				(type default)
			)
			(layer "B.Fab")
		)
		(fp_line
			(start 0.12065 0.3048)
			(end 0.67945 0.3048)
			(stroke
				(width 0.1)
				(type default)
			)
			(layer "B.Fab")
		)
		(fp_line
			(start 0.12065 0.2794)
			(end 0.12065 0.3048)
			(stroke
				(width 0.1)
				(type default)
			)
			(layer "B.Fab")
		)
		(fp_line
			(start 0.12065 -0.2794)
			(end -0.12065 -0.2794)
			(stroke
				(width 0.1)
				(type default)
			)
			(layer "B.Fab")
		)
		(fp_line
			(start 0.12065 -0.305054)
			(end 0.12065 -0.2794)
			(stroke
				(width 0.1)
				(type default)
			)
			(layer "B.Fab")
		)
		(fp_line
			(start -0.120396 0.3048)
			(end -0.120396 0.2794)
			(stroke
				(width 0.1)
				(type default)
			)
			(layer "B.Fab")
		)
		(fp_line
			(start -0.120396 0.2794)
			(end 0.12065 0.2794)
			(stroke
				(width 0.1)
				(type default)
			)
			(layer "B.Fab")
		)
		(fp_line
			(start -0.12065 -0.2794)
			(end -0.12065 -0.3048)
			(stroke
				(width 0.1)
				(type default)
			)
			(layer "B.Fab")
		)
		(fp_line
			(start -0.12065 -0.3048)
			(end -0.67945 -0.3048)
			(stroke
				(width 0.1)
				(type default)
			)
			(layer "B.Fab")
		)
		(fp_line
			(start -0.67945 0.3048)
			(end -0.120396 0.3048)
			(stroke
				(width 0.1)
				(type default)
			)
			(layer "B.Fab")
		)
		(fp_line
			(start -0.67945 -0.3048)
			(end -0.67945 0.3048)
			(stroke
				(width 0.1)
				(type default)
			)
			(layer "B.Fab")
		)
		(pad "1" smd circle
			(at 0.40005 0)
			(size 0 0)
			(layers "B.Cu" "B.Mask" "B.Paste")
			(net "PD_CHK_CPU0_DIMM_SAA")
		)
		(pad "2" smd circle
			(at -0.40005 0)
			(size 0 0)
			(layers "B.Cu" "B.Mask" "B.Paste")
			(net "GND")
		)
	)
	(footprint ""
		(layer "B.Cu")
		(at 315.404246 -416.899344 90)
		(property "Reference" "C6539"
			(at 0 0 90)
			(layer "B.SilkS")
			(hide yes)
			(effects
				(font
					(size 1.27 1.27)
				)
				(justify mirror)
			)
		)
		(property "Value" ""
			(at 0 0 90)
			(layer "B.Fab")
			(effects
				(font
					(size 1.27 1.27)
				)
				(justify mirror)
			)
		)
		(duplicate_pad_numbers_are_jumpers no)
		(fp_line
			(start 0.299974 -0.150114)
			(end -0.299974 -0.150114)
			(stroke
				(width 0.1)
				(type default)
			)
			(layer "B.Fab")
		)
		(fp_line
			(start -0.299974 -0.150114)
			(end -0.299974 0.150114)
			(stroke
				(width 0.1)
				(type default)
			)
			(layer "B.Fab")
		)
		(fp_line
			(start 0.299974 0.150114)
			(end 0.299974 -0.150114)
			(stroke
				(width 0.1)
				(type default)
			)
			(layer "B.Fab")
		)
		(fp_line
			(start -0.299974 0.150114)
			(end 0.299974 0.150114)
			(stroke
				(width 0.1)
				(type default)
			)
			(layer "B.Fab")
		)
		(pad "1" smd rect
			(at 0.2667 0 270)
			(size 0.3048 0.381)
			(layers "B.Cu" "B.Mask" "B.Paste")
			(net "P5E_CPU0_P1_TX_BUF_C_DP<3>")
		)
		(pad "2" smd rect
			(at -0.2667 0 270)
			(size 0.3048 0.381)
			(layers "B.Cu" "B.Mask" "B.Paste")
			(net "P5E_CPU0_P1_TX_BUF_DP<3>")
		)
	)
)
